FILE_TYPE = CONNECTIVITY;
{Allegro Design Entry HDL 16.6-p007 (v16-6-112F) 10/10/2012}
"PAGE_NUMBER" = 124;
0"NC";
1"GND\g";
2"GND\g";
3"GND\g";
4"GND\g";
5"GND\g";
6"GND\g";
%"GND"
"1","(225,825)","0","mstr_symbols","I13";
;
VOLTAGE"0.0V"
CDS_LIB"mstr_symbols"
SIZE"1B"
BODY_TYPE"PLUMBING"
HDL_POWER"GND";
"A\NAC"1;
%"GND"
"1","(2200,4075)","0","mstr_symbols","I14";
;
VOLTAGE"0.0V"
SIZE"1B"
CDS_LIB"mstr_symbols"
BODY_TYPE"PLUMBING"
HDL_POWER"GND";
"A\NAC"2;
%"LBG_CORE_QAT_EXT_D"
"14","(1200,2700)","0","mstr_u_proc","I15";
;
CDS_SEC"14"
LOCATION"U7C1"
PART_NUMBER"H91415-002"
MATERIAL"IC"
PACK_TYPE"BGA1"
SEC_TYPE"BGA1"
SEC"14"
CDS_LIB"mstr_u_proc"
BOM_COST"SB"
CDS_LOCATION"U7C1"
ROOM"SB";
"VSS<74>"
$PN"BK24"1;
"VSS<73>"
$PN"BK27"1;
"VSS<72>"
$PN"BK31"1;
"VSS<71>"
$PN"BK35"1;
"VSS<70>"
$PN"BK38"1;
"VSS<69>"
$PN"BK42"1;
"VSS<68>"
$PN"BK50"1;
"VSS<67>"
$PN"BL22"1;
"VSS<66>"
$PN"BL40"1;
"VSS<65>"
$PN"BL68"1;
"VSS<64>"
$PN"BL37"1;
"VSS<63>"
$PN"BL5"1;
"VSS<62>"
$PN"BL63"1;
"VSS<61>"
$PN"BL70"1;
"VSS<60>"
$PN"BL72"1;
"VSS<59>"
$PN"BM13"1;
"VSS<58>"
$PN"BM17"1;
"VSS<57>"
$PN"BN37"1;
"VSS<56>"
$PN"BM46"1;
"VSS<55>"
$PN"BM50"1;
"VSS<54>"
$PN"BM58"1;
"VSS<53>"
$PN"BM69"1;
"VSS<52>"
$PN"BM71"1;
"VSS<51>"
$PN"BM9"1;
"VSS<50>"
$PN"BN22"1;
"VSS<49>"
$PN"BN59"1;
"VSS<48>"
$PN"BN5"1;
"VSS<47>"
$PN"BN52"1;
"VSS<46>"
$PN"BN66"1;
"VSS<45>"
$PN"BR20"1;
"VSS<44>"
$PN"BR50"1;
"VSS<43>"
$PN"BT8"1;
"VSS<42>"
$PN"BR54"1;
"VSS<41>"
$PN"BR58"1;
"VSS<40>"
$PN"BR6"1;
"VSS<39>"
$PN"BT66"1;
"VSS<38>"
$PN"BU13"1;
"VSS<37>"
$PN"BU11"1;
"VSS<36>"
$PN"BV49"1;
"VSS<35>"
$PN"BU15"1;
"VSS<34>"
$PN"BU18"1;
"VSS<33>"
$PN"BU20"1;
"VSS<32>"
$PN"BU22"1;
"VSS<31>"
$PN"BU24"1;
"VSS<30>"
$PN"BU26"1;
"VSS<29>"
$PN"BU28"1;
"VSS<28>"
$PN"BU30"1;
"VSS<27>"
$PN"BU32"1;
"VSS<26>"
$PN"BU34"1;
"VSS<25>"
$PN"BU37"1;
"VSS<24>"
$PN"BU39"1;
"VSS<23>"
$PN"BU41"1;
"VSS<22>"
$PN"BU43"1;
"VSS<21>"
$PN"BU45"1;
"VSS<20>"
$PN"BU48"1;
"VSS<19>"
$PN"BU50"1;
"VSS<18>"
$PN"BU52"1;
"VSS<17>"
$PN"BU54"1;
"VSS<16>"
$PN"BU57"1;
"VSS<15>"
$PN"BU59"1;
"VSS<14>"
$PN"BU61"1;
"VSS<13>"
$PN"BU63"1;
"VSS<12>"
$PN"BU9"1;
"VSS<11>"
$PN"BV40"1;
"VSS<10>"
$PN"BW15"1;
"VSS<9>"
$PN"BW18"1;
"VSS<8>"
$PN"BW26"1;
"VSS<7>"
$PN"BW52"1;
"VSS<6>"
$PN"BY40"1;
"VSS<5>"
$PN"BY49"1;
"VSS<4>"
$PN"CA15"2;
"VSS<3>"
$PN"CA18"2;
"VSS<2>"
$PN"CA26"2;
"VSS<1>"
$PN"CA50"2;
"VSS<0>"
$PN"CA52"2;
%"LBG_CORE_QAT_EXT_D"
"13","(-1475,2725)","0","mstr_u_proc","I16";
;
CDS_SEC"13"
LOCATION"U7C1"
PART_NUMBER"H91415-002"
MATERIAL"IC"
PACK_TYPE"BGA1"
SEC_TYPE"BGA1"
SEC"13"
CDS_LIB"mstr_u_proc"
BOM_COST"SB"
CDS_LOCATION"U7C1"
ROOM"SB";
"VSS<214>"
$PN"AL68"6;
"VSS<213>"
$PN"AL70"6;
"VSS<212>"
$PN"AL72"6;
"VSS<211>"
$PN"AM26"6;
"VSS<210>"
$PN"AM30"6;
"VSS<209>"
$PN"AM41"6;
"VSS<208>"
$PN"AM46"6;
"VSS<207>"
$PN"AN13"6;
"VSS<206>"
$PN"AN17"6;
"VSS<205>"
$PN"AN68"6;
"VSS<204>"
$PN"AP22"6;
"VSS<203>"
$PN"AN20"6;
"VSS<202>"
$PN"AN5"6;
"VSS<201>"
$PN"AN58"6;
"VSS<200>"
$PN"AN9"6;
"VSS<199>"
$PN"AP2"6;
"VSS<198>"
$PN"AP26"6;
"VSS<197>"
$PN"AP30"6;
"VSS<196>"
$PN"AP4"6;
"VSS<195>"
$PN"AP41"6;
"VSS<194>"
$PN"AP46"6;
"VSS<193>"
$PN"AP52"6;
"VSS<192>"
$PN"AP66"6;
"VSS<191>"
$PN"AR5"6;
"VSS<190>"
$PN"AR50"6;
"VSS<189>"
$PN"AR58"6;
"VSS<188>"
$PN"AR65"6;
"VSS<187>"
$PN"AR68"6;
"VSS<186>"
$PN"AR70"6;
"VSS<185>"
$PN"AR72"6;
"VSS<184>"
$PN"AT7"6;
"VSS<183>"
$PN"AT11"6;
"VSS<182>"
$PN"AT15"6;
"VSS<181>"
$PN"AT18"6;
"VSS<180>"
$PN"AT22"6;
"VSS<179>"
$PN"AT26"6;
"VSS<178>"
$PN"AT30"6;
"VSS<177>"
$PN"AT41"6;
"VSS<176>"
$PN"AT46"6;
"VSS<175>"
$PN"AT59"6;
"VSS<174>"
$PN"AU26"6;
"VSS<173>"
$PN"AU30"6;
"VSS<172>"
$PN"AE22"6;
"VSS<171>"
$PN"AU41"6;
"VSS<170>"
$PN"AU46"6;
"VSS<169>"
$PN"AU50"6;
"VSS<168>"
$PN"AU54"6;
"VSS<167>"
$PN"AU61"6;
"VSS<166>"
$PN"AV5"6;
"VSS<165>"
$PN"AV22"6;
"VSS<164>"
$PN"AV59"6;
"VSS<163>"
$PN"AV68"6;
"VSS<162>"
$PN"AW9"6;
"VSS<161>"
$PN"AW13"6;
"VSS<160>"
$PN"AW17"6;
"VSS<159>"
$PN"AW26"6;
"VSS<158>"
$PN"AW30"6;
"VSS<157>"
$PN"AW32"6;
"VSS<156>"
$PN"AW34"6;
"VSS<155>"
$PN"AW36"6;
"VSS<154>"
$PN"AW37"6;
"VSS<153>"
$PN"AW39"6;
"VSS<152>"
$PN"AW41"6;
"VSS<151>"
$PN"AW46"6;
"VSS<150>"
$PN"AW50"6;
"VSS<149>"
$PN"AW58"6;
"VSS<148>"
$PN"AW61"6;
"VSS<147>"
$PN"AY5"6;
"VSS<146>"
$PN"AY22"6;
"VSS<145>"
$PN"AY56"6;
"VSS<144>"
$PN"AY63"5;
"VSS<143>"
$PN"AY68"5;
"VSS<142>"
$PN"BA50"5;
"VSS<141>"
$PN"BA54"5;
"VSS<140>"
$PN"BA58"5;
"VSS<139>"
$PN"BB5"5;
"VSS<138>"
$PN"BB7"5;
"VSS<137>"
$PN"BB11"5;
"VSS<136>"
$PN"BB15"5;
"VSS<135>"
$PN"BB18"5;
"VSS<134>"
$PN"BB22"5;
"VSS<133>"
$PN"BB44"5;
"VSS<132>"
$PN"BB59"5;
"VSS<131>"
$PN"BB66"5;
"VSS<130>"
$PN"BB68"5;
"VSS<129>"
$PN"BB70"5;
"VSS<128>"
$PN"BB72"5;
"VSS<127>"
$PN"BC69"5;
"VSS<126>"
$PN"BC71"5;
"VSS<125>"
$PN"BD24"5;
"VSS<124>"
$PN"BD27"5;
"VSS<123>"
$PN"BD31"5;
"VSS<122>"
$PN"BD35"5;
"VSS<121>"
$PN"BD5"5;
"VSS<120>"
$PN"BD50"5;
"VSS<119>"
$PN"BD54"5;
"VSS<118>"
$PN"BD68"5;
"VSS<117>"
$PN"BE29"5;
"VSS<116>"
$PN"BE33"5;
"VSS<115>"
$PN"BE37"5;
"VSS<114>"
$PN"BE56"5;
"VSS<113>"
$PN"BE59"5;
"VSS<112>"
$PN"BE63"5;
"VSS<111>"
$PN"BE66"5;
"VSS<110>"
$PN"BF13"5;
"VSS<109>"
$PN"BF17"5;
"VSS<108>"
$PN"BF54"5;
"VSS<107>"
$PN"BG44"5;
"VSS<106>"
$PN"BF20"5;
"VSS<105>"
$PN"BF24"5;
"VSS<104>"
$PN"BF27"5;
"VSS<103>"
$PN"BF38"5;
"VSS<102>"
$PN"BF42"5;
"VSS<101>"
$PN"BF5"5;
"VSS<100>"
$PN"BF50"5;
"VSS<99>"
$PN"BF58"5;
"VSS<98>"
$PN"BF61"5;
"VSS<97>"
$PN"BF65"5;
"VSS<96>"
$PN"BF68"5;
"VSS<95>"
$PN"BF9"5;
"VSS<94>"
$PN"BG33"5;
"VSS<93>"
$PN"BG48"5;
"VSS<92>"
$PN"BG59"5;
"VSS<91>"
$PN"BG63"5;
"VSS<90>"
$PN"BH27"5;
"VSS<89>"
$PN"BH38"5;
"VSS<88>"
$PN"BH42"5;
"VSS<87>"
$PN"BH46"5;
"VSS<86>"
$PN"BH54"5;
"VSS<85>"
$PN"BJ1"5;
"VSS<84>"
$PN"BJ11"5;
"VSS<83>"
$PN"BJ5"5;
"VSS<82>"
$PN"BJ7"5;
"VSS<81>"
$PN"BJ15"5;
"VSS<80>"
$PN"BJ18"5;
"VSS<79>"
$PN"BJ26"5;
"VSS<78>"
$PN"BJ3"5;
"VSS<77>"
$PN"BJ33"5;
"VSS<76>"
$PN"BJ52"5;
"VSS<75>"
$PN"BJ68"5;
%"LBG_CORE_QAT_EXT_D"
"12","(-4000,2700)","0","mstr_u_proc","I17";
;
CDS_SEC"12"
PART_NUMBER"H91415-002"
MATERIAL"IC"
LOCATION"U7C1"
PACK_TYPE"BGA1"
SEC_TYPE"BGA1"
SEC"12"
CDS_LIB"mstr_u_proc"
BOM_COST"SB"
CDS_LOCATION"U7C1"
ROOM"SB";
"VSS<354>"
$PN"N35"4;
"VSS<353>"
$PN"N38"4;
"VSS<352>"
$PN"N46"4;
"VSS<351>"
$PN"N5"4;
"VSS<350>"
$PN"R38"4;
"VSS<349>"
$PN"N68"4;
"VSS<348>"
$PN"N9"4;
"VSS<347>"
$PN"AE43"4;
"VSS<346>"
$PN"P63"4;
"VSS<345>"
$PN"R27"4;
"VSS<344>"
$PN"U42"4;
"VSS<343>"
$PN"R5"4;
"VSS<342>"
$PN"R50"4;
"VSS<341>"
$PN"R54"4;
"VSS<340>"
$PN"T56"4;
"VSS<339>"
$PN"R58"4;
"VSS<338>"
$PN"R68"4;
"VSS<337>"
$PN"T11"4;
"VSS<336>"
$PN"T15"4;
"VSS<335>"
$PN"T18"4;
"VSS<334>"
$PN"T22"4;
"VSS<333>"
$PN"T26"4;
"VSS<332>"
$PN"T29"4;
"VSS<331>"
$PN"T33"4;
"VSS<330>"
$PN"T37"4;
"VSS<329>"
$PN"T40"4;
"VSS<328>"
$PN"AJ45"4;
"VSS<327>"
$PN"T48"4;
"VSS<326>"
$PN"T52"4;
"VSS<325>"
$PN"T66"4;
"VSS<324>"
$PN"T7"4;
"VSS<323>"
$PN"AF50"4;
"VSS<322>"
$PN"AG46"4;
"VSS<321>"
$PN"U58"4;
"VSS<320>"
$PN"V26"4;
"VSS<319>"
$PN"V48"4;
"VSS<318>"
$PN"V5"4;
"VSS<317>"
$PN"V52"4;
"VSS<316>"
$PN"W58"4;
"VSS<315>"
$PN"V66"4;
"VSS<314>"
$PN"V68"4;
"VSS<313>"
$PN"W13"4;
"VSS<312>"
$PN"W17"4;
"VSS<311>"
$PN"W20"4;
"VSS<310>"
$PN"W24"4;
"VSS<309>"
$PN"AA50"4;
"VSS<308>"
$PN"Y43"4;
"VSS<307>"
$PN"W61"4;
"VSS<306>"
$PN"W9"4;
"VSS<305>"
$PN"Y22"4;
"VSS<304>"
$PN"Y27"4;
"VSS<303>"
$PN"Y48"4;
"VSS<302>"
$PN"Y5"4;
"VSS<301>"
$PN"Y52"4;
"VSS<300>"
$PN"Y59"4;
"VSS<299>"
$PN"Y63"4;
"VSS<298>"
$PN"Y68"4;
"VSS<297>"
$PN"AA26"4;
"VSS<296>"
$PN"AA27"4;
"VSS<295>"
$PN"AA43"4;
"VSS<294>"
$PN"AA48"4;
"VSS<293>"
$PN"AB5"4;
"VSS<292>"
$PN"AB68"4;
"VSS<291>"
$PN"AB70"4;
"VSS<290>"
$PN"AB72"4;
"VSS<289>"
$PN"AC11"4;
"VSS<288>"
$PN"AC15"4;
"VSS<287>"
$PN"AC18"4;
"VSS<286>"
$PN"AC22"4;
"VSS<285>"
$PN"AC45"4;
"VSS<284>"
$PN"AD58"3;
"VSS<283>"
$PN"AC27"3;
"VSS<282>"
$PN"AC43"3;
"VSS<281>"
$PN"AC46"3;
"VSS<280>"
$PN"AC48"3;
"VSS<279>"
$PN"AC52"3;
"VSS<278>"
$PN"AC59"3;
"VSS<277>"
$PN"AC63"3;
"VSS<276>"
$PN"AC66"3;
"VSS<275>"
$PN"AC7"3;
"VSS<274>"
$PN"AD5"3;
"VSS<273>"
$PN"AD65"3;
"VSS<272>"
$PN"AD68"3;
"VSS<271>"
$PN"AE29"3;
"VSS<270>"
$PN"J18"3;
"VSS<269>"
$PN"AE48"3;
"VSS<268>"
$PN"AE52"3;
"VSS<267>"
$PN"AE56"3;
"VSS<266>"
$PN"AE59"3;
"VSS<265>"
$PN"AE63"3;
"VSS<264>"
$PN"AE66"3;
"VSS<263>"
$PN"AF1"3;
"VSS<262>"
$PN"AF13"3;
"VSS<261>"
$PN"AF5"3;
"VSS<260>"
$PN"AF9"3;
"VSS<259>"
$PN"AF17"3;
"VSS<258>"
$PN"AF24"3;
"VSS<257>"
$PN"AF3"3;
"VSS<256>"
$PN"AF68"3;
"VSS<255>"
$PN"AG26"3;
"VSS<254>"
$PN"AG30"3;
"VSS<253>"
$PN"AG41"3;
"VSS<252>"
$PN"AG43"3;
"VSS<251>"
$PN"AG52"3;
"VSS<250>"
$PN"AG56"3;
"VSS<249>"
$PN"AG59"3;
"VSS<248>"
$PN"AG66"3;
"VSS<247>"
$PN"AH20"3;
"VSS<246>"
$PN"AJ11"3;
"VSS<245>"
$PN"AJ32"3;
"VSS<244>"
$PN"AJ56"3;
"VSS<243>"
$PN"AK30"3;
"VSS<242>"
$PN"AJ15"3;
"VSS<241>"
$PN"AJ18"3;
"VSS<240>"
$PN"AJ22"3;
"VSS<239>"
$PN"AJ26"3;
"VSS<238>"
$PN"AJ30"3;
"VSS<237>"
$PN"AJ34"3;
"VSS<236>"
$PN"AJ36"3;
"VSS<235>"
$PN"AJ37"3;
"VSS<234>"
$PN"AJ39"3;
"VSS<233>"
$PN"AJ41"3;
"VSS<232>"
$PN"AJ5"3;
"VSS<231>"
$PN"AJ52"3;
"VSS<230>"
$PN"AJ59"3;
"VSS<229>"
$PN"AJ66"3;
"VSS<228>"
$PN"AJ68"3;
"VSS<227>"
$PN"AJ7"3;
"VSS<226>"
$PN"AK26"3;
"VSS<225>"
$PN"AK41"3;
"VSS<224>"
$PN"AK46"3;
"VSS<223>"
$PN"AK48"3;
"VSS<222>"
$PN"AK58"3;
"VSS<221>"
$PN"AK61"3;
"VSS<220>"
$PN"AK69"3;
"VSS<219>"
$PN"AK71"3;
"VSS<218>"
$PN"AL22"3;
"VSS<217>"
$PN"AL5"3;
"VSS<216>"
$PN"AL52"3;
"VSS<215>"
$PN"AL59"3;
%"GND"
"1","(-3125,600)","0","mstr_symbols","I4";
;
VOLTAGE"0.0V"
SIZE"1B"
CDS_LIB"mstr_symbols"
BODY_TYPE"PLUMBING"
HDL_POWER"GND";
"A\NAC"3;
%"GND"
"1","(-4950,600)","0","mstr_symbols","I6";
;
VOLTAGE"0.0V"
SIZE"1B"
CDS_LIB"mstr_symbols"
BODY_TYPE"PLUMBING"
HDL_POWER"GND";
"A\NAC"4;
%"GND"
"1","(-400,575)","0","mstr_symbols","I7";
;
VOLTAGE"0.0V"
CDS_LIB"mstr_symbols"
SIZE"1B"
BODY_TYPE"PLUMBING"
HDL_POWER"GND";
"A\NAC"5;
%"GND"
"1","(-2550,625)","0","mstr_symbols","I9";
;
VOLTAGE"0.0V"
SIZE"1B"
CDS_LIB"mstr_symbols"
BODY_TYPE"PLUMBING"
HDL_POWER"GND";
"A\NAC"6;
END.
